(kicad_pcb
	(version 20241229)
	(generator "pcbnew")
	(generator_version "9.0")
	(general
		(thickness 1.6)
		(legacy_teardrops no)
	)
	(paper "A4")
	(title_block
		(title "LPDDR4 testbed")
		(date "2024-03-26")
		(rev "1.2.2")
		(comment 9 "footprint 1 of 66 (J1), pads 101-197 of 262")
	)
	(layers
		(0 "F.Cu" signal)
		(4 "In1.Cu" power)
		(6 "In2.Cu" power)
		(8 "In3.Cu" signal)
		(10 "In4.Cu" signal)
		(2 "B.Cu" signal)
		(9 "F.Adhes" user "F.Adhesive")
		(11 "B.Adhes" user "B.Adhesive")
		(13 "F.Paste" user)
		(15 "B.Paste" user)
		(5 "F.SilkS" user "F.Silkscreen")
		(7 "B.SilkS" user "B.Silkscreen")
		(1 "F.Mask" user)
		(3 "B.Mask" user)
		(17 "Dwgs.User" user "User.Drawings")
		(19 "Cmts.User" user "User.Comments")
		(21 "Eco1.User" user "User.Eco1")
		(23 "Eco2.User" user "User.Eco2")
		(25 "Edge.Cuts" user)
		(27 "Margin" user)
		(31 "F.CrtYd" user "F.Courtyard")
		(29 "B.CrtYd" user "B.Courtyard")
		(35 "F.Fab" user)
		(33 "B.Fab" user)
	)
	(footprint "antmicro-footprints:Edge_Conn_Bus_DDR4"
		(locked yes)
		(layer "F.Cu")
		(at 100 100)
		(descr "SODIMM DDR4 Edge Connector")
		(tags "SODIMM DDR4 Edge Connector")
		(property "Reference" "J1"
			(at 0 -4.2 0)
			(layer "F.SilkS")
			(hide yes)
			(effects
				(font
					(size 0.7 0.7)
					(thickness 0.15)
				)
				(justify left bottom)
			)
		)
		(property "Value" "Bus_DDR4_Edge_Conn"
			(at 0 1 0)
			(layer "F.Fab")
			(effects
				(font
					(size 0.7 0.7)
					(thickness 0.15)
				)
				(justify left bottom)
			)
		)
		(property "Description" "DDR SO-DIMM PCB Edge"
			(at 0 0 0)
			(layer "F.Fab")
			(hide yes)
			(effects
				(font
					(size 1.27 1.27)
					(thickness 0.15)
				)
			)
		)
		(property "Author" "Antmicro"
			(at 0 0 0)
			(layer "F.Fab")
			(hide yes)
			(effects
				(font
					(size 1 1)
					(thickness 0.15)
				)
			)
		)
		(property "License" "Apache-2.0"
			(at 0 0 0)
			(layer "F.Fab")
			(hide yes)
			(effects
				(font
					(size 1 1)
					(thickness 0.15)
				)
			)
		)
		(property "MPN" ""
			(at 0 0 0)
			(layer "F.Fab")
			(hide yes)
			(effects
				(font
					(size 1 1)
					(thickness 0.15)
				)
			)
		)
		(property "Manufacturer" ""
			(at 0 0 0)
			(layer "F.Fab")
			(hide yes)
			(effects
				(font
					(size 1 1)
					(thickness 0.15)
				)
			)
		)
		(sheetname "SODIMM")
		(sheetfile "sodim.kicad_sch")
		(attr exclude_from_pos_files exclude_from_bom)
		(pad "99" smd rect
			(at 25.925 -1.301)
			(size 0.35 2.5)
			(layers "F.Cu" "F.Mask")
			(net 188 "VDD2")
			(pinfunction "99")
			(pintype "passive")
		)
		(pad "100" smd rect
			(at 26.175 -1.301)
			(size 0.35 2.5)
			(layers "B.Cu" "B.Mask")
			(net 50 "unconnected-(J1-Pad100)")
			(pinfunction "100")
			(pintype "passive+no_connect")
		)
		(pad "101" smd rect
			(at 26.425 -1.301)
			(size 0.35 2.5)
			(layers "F.Cu" "F.Mask")
			(net 188 "VDD2")
			(pinfunction "101")
			(pintype "passive")
		)
		(pad "102" smd rect
			(at 26.675 -1.301)
			(size 0.35 2.5)
			(layers "B.Cu" "B.Mask")
			(net 51 "unconnected-(J1-Pad102)")
			(pinfunction "102")
			(pintype "passive+no_connect")
		)
		(pad "103" smd rect
			(at 26.925 -1.301)
			(size 0.35 2.5)
			(layers "F.Cu" "F.Mask")
			(net 188 "VDD2")
			(pinfunction "103")
			(pintype "passive")
		)
		(pad "104" smd rect
			(at 27.175 -1.301)
			(size 0.35 2.5)
			(layers "B.Cu" "B.Mask")
			(net 52 "unconnected-(J1-Pad104)")
			(pinfunction "104")
			(pintype "passive+no_connect")
		)
		(pad "105" smd rect
			(at 27.425 -1.301)
			(size 0.35 2.5)
			(layers "F.Cu" "F.Mask")
			(net 188 "VDD2")
			(pinfunction "105")
			(pintype "passive")
		)
		(pad "106" smd rect
			(at 27.675 -1.301)
			(size 0.35 2.5)
			(layers "B.Cu" "B.Mask")
			(net 53 "unconnected-(J1-Pad106)")
			(pinfunction "106")
			(pintype "passive+no_connect")
		)
		(pad "107" smd rect
			(at 27.925 -1.301)
			(size 0.35 2.5)
			(layers "F.Cu" "F.Mask")
			(net 188 "VDD2")
			(pinfunction "107")
			(pintype "passive")
		)
		(pad "108" smd rect
			(at 28.175 -1.301)
			(size 0.35 2.5)
			(layers "B.Cu" "B.Mask")
			(net 54 "unconnected-(J1-Pad108)")
			(pinfunction "108")
			(pintype "passive+no_connect")
		)
		(pad "109" smd rect
			(at 28.425 -1.301)
			(size 0.35 2.5)
			(layers "F.Cu" "F.Mask")
			(net 55 "unconnected-(J1-Pad109)")
			(pinfunction "109")
			(pintype "passive+no_connect")
		)
		(pad "110" smd rect
			(at 28.675 -1.301)
			(size 0.35 2.5)
			(layers "B.Cu" "B.Mask")
			(net 56 "unconnected-(J1-Pad110)")
			(pinfunction "110")
			(pintype "passive+no_connect")
		)
		(pad "111" smd rect
			(at 28.925 -1.301)
			(size 0.35 2.5)
			(layers "F.Cu" "F.Mask")
			(net 57 "unconnected-(J1-Pad111)")
			(pinfunction "111")
			(pintype "passive+no_connect")
		)
		(pad "112" smd rect
			(at 29.175 -1.301)
			(size 0.35 2.5)
			(layers "B.Cu" "B.Mask")
			(net 58 "unconnected-(J1-Pad112)")
			(pinfunction "112")
			(pintype "passive+no_connect")
		)
		(pad "113" smd rect
			(at 29.425 -1.301)
			(size 0.35 2.5)
			(layers "F.Cu" "F.Mask")
			(net 59 "unconnected-(J1-Pad113)")
			(pinfunction "113")
			(pintype "passive+no_connect")
		)
		(pad "114" smd rect
			(at 29.675 -1.301)
			(size 0.35 2.5)
			(layers "B.Cu" "B.Mask")
			(net 60 "unconnected-(J1-Pad114)")
			(pinfunction "114")
			(pintype "passive+no_connect")
		)
		(pad "115" smd rect
			(at 29.925 -1.301)
			(size 0.35 2.5)
			(layers "F.Cu" "F.Mask")
			(net 61 "unconnected-(J1-Pad115)")
			(pinfunction "115")
			(pintype "passive+no_connect")
		)
		(pad "116" smd rect
			(at 30.175 -1.301)
			(size 0.35 2.5)
			(layers "B.Cu" "B.Mask")
			(net 187 "VDD1")
			(pinfunction "116")
			(pintype "passive")
		)
		(pad "117" smd rect
			(at 30.425 -1.301)
			(size 0.35 2.5)
			(layers "F.Cu" "F.Mask")
			(net 62 "unconnected-(J1-Pad117)")
			(pinfunction "117")
			(pintype "passive+no_connect")
		)
		(pad "118" smd rect
			(at 30.675 -1.301)
			(size 0.35 2.5)
			(layers "B.Cu" "B.Mask")
			(net 187 "VDD1")
			(pinfunction "118")
			(pintype "passive")
		)
		(pad "119" smd rect
			(at 30.925 -1.301)
			(size 0.35 2.5)
			(layers "F.Cu" "F.Mask")
			(net 63 "unconnected-(J1-Pad119)")
			(pinfunction "119")
			(pintype "passive+no_connect")
		)
		(pad "120" smd rect
			(at 31.175 -1.301)
			(size 0.35 2.5)
			(layers "B.Cu" "B.Mask")
			(net 187 "VDD1")
			(pinfunction "120")
			(pintype "passive")
		)
		(pad "121" smd rect
			(at 31.425 -1.301)
			(size 0.35 2.5)
			(layers "F.Cu" "F.Mask")
			(net 64 "unconnected-(J1-Pad121)")
			(pinfunction "121")
			(pintype "passive+no_connect")
		)
		(pad "122" smd rect
			(at 31.675 -1.301)
			(size 0.35 2.5)
			(layers "B.Cu" "B.Mask")
			(net 187 "VDD1")
			(pinfunction "122")
			(pintype "passive")
		)
		(pad "123" smd rect
			(at 31.925 -1.301)
			(size 0.35 2.5)
			(layers "F.Cu" "F.Mask")
			(net 65 "unconnected-(J1-Pad123)")
			(pinfunction "123")
			(pintype "passive+no_connect")
		)
		(pad "124" smd rect
			(at 32.173 -1.301)
			(size 0.35 2.5)
			(layers "B.Cu" "B.Mask")
			(net 187 "VDD1")
			(pinfunction "124")
			(pintype "passive")
		)
		(pad "125" smd rect
			(at 32.423 -1.301)
			(size 0.35 2.5)
			(layers "F.Cu" "F.Mask")
			(net 66 "unconnected-(J1-Pad125)")
			(pinfunction "125")
			(pintype "passive+no_connect")
		)
		(pad "126" smd rect
			(at 32.673 -1.301)
			(size 0.35 2.5)
			(layers "B.Cu" "B.Mask")
			(net 189 "VDDQ")
			(pinfunction "126")
			(pintype "passive")
		)
		(pad "127" smd rect
			(at 32.923 -1.301)
			(size 0.35 2.5)
			(layers "F.Cu" "F.Mask")
			(net 246 "SDA")
			(pinfunction "127")
			(pintype "passive")
		)
		(pad "128" smd rect
			(at 33.173 -1.301)
			(size 0.35 2.5)
			(layers "B.Cu" "B.Mask")
			(net 189 "VDDQ")
			(pinfunction "128")
			(pintype "passive")
		)
		(pad "129" smd rect
			(at 33.423 -1.301)
			(size 0.35 2.5)
			(layers "F.Cu" "F.Mask")
			(net 247 "SCL")
			(pinfunction "129")
			(pintype "passive")
		)
		(pad "130" smd rect
			(at 33.673 -1.301)
			(size 0.35 2.5)
			(layers "B.Cu" "B.Mask")
			(net 189 "VDDQ")
			(pinfunction "130")
			(pintype "passive")
		)
		(pad "131" smd rect
			(at 33.923 -1.301)
			(size 0.35 2.5)
			(layers "F.Cu" "F.Mask")
			(net 67 "unconnected-(J1-Pad131)")
			(pinfunction "131")
			(pintype "passive+no_connect")
		)
		(pad "132" smd rect
			(at 34.173 -1.301)
			(size 0.35 2.5)
			(layers "B.Cu" "B.Mask")
			(net 68 "unconnected-(J1-Pad132)")
			(pinfunction "132")
			(pintype "passive+no_connect")
		)
		(pad "133" smd rect
			(at 34.423 -1.301)
			(size 0.35 2.5)
			(layers "F.Cu" "F.Mask")
			(net 69 "unconnected-(J1-Pad133)")
			(pinfunction "133")
			(pintype "passive+no_connect")
		)
		(pad "134" smd rect
			(at 34.673 -1.301)
			(size 0.35 2.5)
			(layers "B.Cu" "B.Mask")
			(net 70 "unconnected-(J1-Pad134)")
			(pinfunction "134")
			(pintype "passive+no_connect")
		)
		(pad "135" smd rect
			(at 34.923 -1.301)
			(size 0.35 2.5)
			(layers "F.Cu" "F.Mask")
			(net 71 "unconnected-(J1-Pad135)")
			(pinfunction "135")
			(pintype "passive+no_connect")
		)
		(pad "136" smd rect
			(at 35.173 -1.301)
			(size 0.35 2.5)
			(layers "B.Cu" "B.Mask")
			(net 72 "unconnected-(J1-Pad136)")
			(pinfunction "136")
			(pintype "passive+no_connect")
		)
		(pad "137" smd rect
			(at 35.423 -1.301)
			(size 0.35 2.5)
			(layers "F.Cu" "F.Mask")
			(net 73 "unconnected-(J1-Pad137)")
			(pinfunction "137")
			(pintype "passive+no_connect")
		)
		(pad "138" smd rect
			(at 35.673 -1.301)
			(size 0.35 2.5)
			(layers "B.Cu" "B.Mask")
			(net 74 "unconnected-(J1-Pad138)")
			(pinfunction "138")
			(pintype "passive+no_connect")
		)
		(pad "139" smd rect
			(at 35.923 -1.301)
			(size 0.35 2.5)
			(layers "F.Cu" "F.Mask")
			(net 75 "unconnected-(J1-Pad139)")
			(pinfunction "139")
			(pintype "passive+no_connect")
		)
		(pad "140" smd rect
			(at 36.173 -1.301)
			(size 0.35 2.5)
			(layers "B.Cu" "B.Mask")
			(net 76 "unconnected-(J1-Pad140)")
			(pinfunction "140")
			(pintype "passive+no_connect")
		)
		(pad "141" smd rect
			(at 36.423 -1.301)
			(size 0.35 2.5)
			(layers "F.Cu" "F.Mask")
			(net 77 "unconnected-(J1-Pad141)")
			(pinfunction "141")
			(pintype "passive+no_connect")
		)
		(pad "142" smd rect
			(at 36.673 -1.301)
			(size 0.35 2.5)
			(layers "B.Cu" "B.Mask")
			(net 78 "unconnected-(J1-Pad142)")
			(pinfunction "142")
			(pintype "passive+no_connect")
		)
		(pad "143" smd rect
			(at 36.923 -1.301)
			(size 0.35 2.5)
			(layers "F.Cu" "F.Mask")
			(net 79 "unconnected-(J1-Pad143)")
			(pinfunction "143")
			(pintype "passive+no_connect")
		)
		(pad "144" smd rect
			(at 37.173 -1.301)
			(size 0.35 2.5)
			(layers "B.Cu" "B.Mask")
			(net 80 "unconnected-(J1-Pad144)")
			(pinfunction "144")
			(pintype "passive+no_connect")
		)
		(pad "145" smd rect
			(at 39.423 -1.301)
			(size 0.35 2.5)
			(layers "F.Cu" "F.Mask")
			(net 81 "unconnected-(J1-Pad145)")
			(pinfunction "145")
			(pintype "passive+no_connect")
		)
		(pad "146" smd rect
			(at 39.673 -1.301)
			(size 0.35 2.5)
			(layers "B.Cu" "B.Mask")
			(net 82 "unconnected-(J1-Pad146)")
			(pinfunction "146")
			(pintype "passive+no_connect")
		)
		(pad "147" smd rect
			(at 39.923 -1.301)
			(size 0.35 2.5)
			(layers "F.Cu" "F.Mask")
			(net 83 "unconnected-(J1-Pad147)")
			(pinfunction "147")
			(pintype "passive+no_connect")
		)
		(pad "148" smd rect
			(at 40.173 -1.301)
			(size 0.35 2.5)
			(layers "B.Cu" "B.Mask")
			(net 84 "unconnected-(J1-Pad148)")
			(pinfunction "148")
			(pintype "passive+no_connect")
		)
		(pad "149" smd rect
			(at 40.423 -1.301)
			(size 0.35 2.5)
			(layers "F.Cu" "F.Mask")
			(net 85 "unconnected-(J1-Pad149)")
			(pinfunction "149")
			(pintype "passive+no_connect")
		)
		(pad "150" smd rect
			(at 40.673 -1.301)
			(size 0.35 2.5)
			(layers "B.Cu" "B.Mask")
			(net 86 "unconnected-(J1-Pad150)")
			(pinfunction "150")
			(pintype "passive+no_connect")
		)
		(pad "151" smd rect
			(at 40.923 -1.301)
			(size 0.35 2.5)
			(layers "F.Cu" "F.Mask")
			(net 87 "unconnected-(J1-Pad151)")
			(pinfunction "151")
			(pintype "passive+no_connect")
		)
		(pad "152" smd rect
			(at 41.173 -1.301)
			(size 0.35 2.5)
			(layers "B.Cu" "B.Mask")
			(net 88 "unconnected-(J1-Pad152)")
			(pinfunction "152")
			(pintype "passive+no_connect")
		)
		(pad "153" smd rect
			(at 41.423 -1.301)
			(size 0.35 2.5)
			(layers "F.Cu" "F.Mask")
			(net 89 "unconnected-(J1-Pad153)")
			(pinfunction "153")
			(pintype "passive+no_connect")
		)
		(pad "154" smd rect
			(at 41.673 -1.301)
			(size 0.35 2.5)
			(layers "B.Cu" "B.Mask")
			(net 36 "GND")
			(pinfunction "154")
			(pintype "passive")
		)
		(pad "155" smd rect
			(at 41.923 -1.301)
			(size 0.35 2.5)
			(layers "F.Cu" "F.Mask")
			(net 90 "unconnected-(J1-Pad155)")
			(pinfunction "155")
			(pintype "passive+no_connect")
		)
		(pad "156" smd rect
			(at 42.173 -1.301)
			(size 0.35 2.5)
			(layers "B.Cu" "B.Mask")
			(net 221 "CA5_A")
			(pinfunction "156")
			(pintype "passive")
		)
		(pad "157" smd rect
			(at 42.423 -1.301)
			(size 0.35 2.5)
			(layers "F.Cu" "F.Mask")
			(net 91 "unconnected-(J1-Pad157)")
			(pinfunction "157")
			(pintype "passive+no_connect")
		)
		(pad "158" smd rect
			(at 42.673 -1.301)
			(size 0.35 2.5)
			(layers "B.Cu" "B.Mask")
			(net 220 "CA4_A")
			(pinfunction "158")
			(pintype "passive")
		)
		(pad "159" smd rect
			(at 42.923 -1.301)
			(size 0.35 2.5)
			(layers "F.Cu" "F.Mask")
			(net 92 "unconnected-(J1-Pad159)")
			(pinfunction "159")
			(pintype "passive+no_connect")
		)
		(pad "160" smd rect
			(at 43.173 -1.301)
			(size 0.35 2.5)
			(layers "B.Cu" "B.Mask")
			(net 219 "CA3_A")
			(pinfunction "160")
			(pintype "passive")
		)
		(pad "161" smd rect
			(at 43.423 -1.301)
			(size 0.35 2.5)
			(layers "F.Cu" "F.Mask")
			(net 36 "GND")
			(pinfunction "161")
			(pintype "passive")
		)
		(pad "162" smd rect
			(at 43.673 -1.301)
			(size 0.35 2.5)
			(layers "B.Cu" "B.Mask")
			(net 218 "CA2_A")
			(pinfunction "162")
			(pintype "passive")
		)
		(pad "163" smd rect
			(at 43.923 -1.301)
			(size 0.35 2.5)
			(layers "F.Cu" "F.Mask")
			(net 217 "DQ11_A")
			(pinfunction "163")
			(pintype "passive")
		)
		(pad "164" smd rect
			(at 44.173 -1.301)
			(size 0.35 2.5)
			(layers "B.Cu" "B.Mask")
			(net 214 "CK_C_A")
			(pinfunction "164")
			(pintype "passive")
		)
		(pad "165" smd rect
			(at 44.423 -1.301)
			(size 0.35 2.5)
			(layers "F.Cu" "F.Mask")
			(net 215 "DQ10_A")
			(pinfunction "165")
			(pintype "passive")
		)
		(pad "166" smd rect
			(at 44.673 -1.301)
			(size 0.35 2.5)
			(layers "B.Cu" "B.Mask")
			(net 216 "CK_T_A")
			(pinfunction "166")
			(pintype "passive")
		)
		(pad "167" smd rect
			(at 44.923 -1.301)
			(size 0.35 2.5)
			(layers "F.Cu" "F.Mask")
			(net 213 "DQ09_A")
			(pinfunction "167")
			(pintype "passive")
		)
		(pad "168" smd rect
			(at 45.173 -1.301)
			(size 0.35 2.5)
			(layers "B.Cu" "B.Mask")
			(net 36 "GND")
			(pinfunction "168")
			(pintype "passive")
		)
		(pad "169" smd rect
			(at 45.423 -1.301)
			(size 0.35 2.5)
			(layers "F.Cu" "F.Mask")
			(net 212 "DQ08_A")
			(pinfunction "169")
			(pintype "passive")
		)
		(pad "170" smd rect
			(at 45.673 -1.301)
			(size 0.35 2.5)
			(layers "B.Cu" "B.Mask")
			(net 93 "unconnected-(J1-Pad170)")
			(pinfunction "170")
			(pintype "passive+no_connect")
		)
		(pad "171" smd rect
			(at 45.923 -1.301)
			(size 0.35 2.5)
			(layers "F.Cu" "F.Mask")
			(net 211 "DMI_1A")
			(pinfunction "171")
			(pintype "passive")
		)
		(pad "172" smd rect
			(at 46.173 -1.301)
			(size 0.35 2.5)
			(layers "B.Cu" "B.Mask")
			(net 94 "unconnected-(J1-Pad172)")
			(pinfunction "172")
			(pintype "passive+no_connect")
		)
		(pad "173" smd rect
			(at 46.423 -1.301)
			(size 0.35 2.5)
			(layers "F.Cu" "F.Mask")
			(net 210 "DQ_S1_CA")
			(pinfunction "173")
			(pintype "passive")
		)
		(pad "174" smd rect
			(at 46.673 -1.301)
			(size 0.35 2.5)
			(layers "B.Cu" "B.Mask")
			(net 95 "unconnected-(J1-Pad174)")
			(pinfunction "174")
			(pintype "passive+no_connect")
		)
		(pad "175" smd rect
			(at 46.923 -1.301)
			(size 0.35 2.5)
			(layers "F.Cu" "F.Mask")
			(net 209 "DQ_S1_TA")
			(pinfunction "175")
			(pintype "passive")
		)
		(pad "176" smd rect
			(at 47.173 -1.301)
			(size 0.35 2.5)
			(layers "B.Cu" "B.Mask")
			(net 96 "unconnected-(J1-Pad176)")
			(pinfunction "176")
			(pintype "passive+no_connect")
		)
		(pad "177" smd rect
			(at 47.423 -1.301)
			(size 0.35 2.5)
			(layers "F.Cu" "F.Mask")
			(net 36 "GND")
			(pinfunction "177")
			(pintype "passive")
		)
		(pad "178" smd rect
			(at 47.673 -1.301)
			(size 0.35 2.5)
			(layers "B.Cu" "B.Mask")
			(net 97 "unconnected-(J1-Pad178)")
			(pinfunction "178")
			(pintype "passive+no_connect")
		)
		(pad "179" smd rect
			(at 47.923 -1.301)
			(size 0.35 2.5)
			(layers "F.Cu" "F.Mask")
			(net 208 "DQ15_A")
			(pinfunction "179")
			(pintype "passive")
		)
		(pad "180" smd rect
			(at 48.173 -1.301)
			(size 0.35 2.5)
			(layers "B.Cu" "B.Mask")
			(net 98 "unconnected-(J1-Pad180)")
			(pinfunction "180")
			(pintype "passive+no_connect")
		)
		(pad "181" smd rect
			(at 48.423 -1.301)
			(size 0.35 2.5)
			(layers "F.Cu" "F.Mask")
			(net 207 "DQ14_A")
			(pinfunction "181")
			(pintype "passive")
		)
		(pad "182" smd rect
			(at 48.673 -1.301)
			(size 0.35 2.5)
			(layers "B.Cu" "B.Mask")
			(net 99 "unconnected-(J1-Pad182)")
			(pinfunction "182")
			(pintype "passive+no_connect")
		)
		(pad "183" smd rect
			(at 48.923 -1.301)
			(size 0.35 2.5)
			(layers "F.Cu" "F.Mask")
			(net 206 "DQ13_A")
			(pinfunction "183")
			(pintype "passive")
		)
		(pad "184" smd rect
			(at 49.173 -1.301)
			(size 0.35 2.5)
			(layers "B.Cu" "B.Mask")
			(net 36 "GND")
			(pinfunction "184")
			(pintype "passive")
		)
		(pad "185" smd rect
			(at 49.423 -1.301)
			(size 0.35 2.5)
			(layers "F.Cu" "F.Mask")
			(net 205 "DQ12_A")
			(pinfunction "185")
			(pintype "passive")
		)
		(pad "186" smd rect
			(at 49.673 -1.301)
			(size 0.35 2.5)
			(layers "B.Cu" "B.Mask")
			(net 230 "RESET_N")
			(pinfunction "186")
			(pintype "passive")
		)
		(pad "187" smd rect
			(at 49.923 -1.301)
			(size 0.35 2.5)
			(layers "F.Cu" "F.Mask")
			(net 204 "DQ04_A")
			(pinfunction "187")
			(pintype "passive")
		)
		(pad "188" smd rect
			(at 50.173 -1.301)
			(size 0.35 2.5)
			(layers "B.Cu" "B.Mask")
			(net 100 "unconnected-(J1-Pad188)")
			(pinfunction "188")
			(pintype "passive+no_connect")
		)
		(pad "189" smd rect
			(at 50.423 -1.301)
			(size 0.35 2.5)
			(layers "F.Cu" "F.Mask")
			(net 203 "DQ05_A")
			(pinfunction "189")
			(pintype "passive")
		)
		(pad "190" smd rect
			(at 50.673 -1.301)
			(size 0.35 2.5)
			(layers "B.Cu" "B.Mask")
			(net 101 "unconnected-(J1-Pad190)")
			(pinfunction "190")
			(pintype "passive+no_connect")
		)
		(pad "191" smd rect
			(at 50.923 -1.301)
			(size 0.35 2.5)
			(layers "F.Cu" "F.Mask")
			(net 202 "DQ06_A")
			(pinfunction "191")
			(pintype "passive")
		)
		(pad "192" smd rect
			(at 51.173 -1.301)
			(size 0.35 2.5)
			(layers "B.Cu" "B.Mask")
			(net 229 "ODT_CA_A")
			(pinfunction "192")
			(pintype "passive")
		)
		(pad "193" smd rect
			(at 51.423 -1.301)
			(size 0.35 2.5)
			(layers "F.Cu" "F.Mask")
			(net 198 "DQ07_A")
			(pinfunction "193")
			(pintype "passive")
		)
		(pad "194" smd rect
			(at 51.673 -1.301)
			(size 0.35 2.5)
			(layers "B.Cu" "B.Mask")
			(net 200 "CS0_A")
			(pinfunction "194")
			(pintype "passive")
		)
		(pad "195" smd rect
			(at 51.923 -1.301)
			(size 0.35 2.5)
			(layers "F.Cu" "F.Mask")
			(net 36 "GND")
			(pinfunction "195")
			(pintype "passive")
		)
	)
)
